(kicad_pcb
	(version 20260206)
	(generator "pcbnew")
	(generator_version "10.0")
	(general
		(thickness 1.6)
		(legacy_teardrops no)
	)
	(paper "A4")
	(title_block
		(title "v1-chassis-manager — T6M_CM_d_v01_1031_1645.brd")
		(comment 1 "Open CloudServer (Microsoft) / footprints 1905-1914 of 2512")
	)
	(layers
		(0 "F.Cu" signal "TOP")
		(4 "In1.Cu" signal "GND1")
		(6 "In2.Cu" signal "IN1")
		(8 "In3.Cu" signal "VCC1")
		(10 "In4.Cu" signal "VCC2")
		(12 "In5.Cu" signal "GND2")
		(14 "In6.Cu" signal "IN2")
		(16 "In7.Cu" signal "IN3")
		(18 "In8.Cu" signal "GND3")
		(2 "B.Cu" signal "BOTTOM")
		(9 "F.Adhes" user "F.Adhesive")
		(11 "B.Adhes" user "B.Adhesive")
		(13 "F.Paste" user "Package Geometry/Pastemask Top")
		(15 "B.Paste" user "Package Geometry/Pastemask Bottom")
		(5 "F.SilkS" user "Ref Des/Silkscreen Top")
		(7 "B.SilkS" user "Ref Des/Silkscreen Bottom")
		(1 "F.Mask" user "Board Geometry/Soldermask Top")
		(3 "B.Mask" user "Board Geometry/Soldermask Bottom")
		(17 "Dwgs.User" user "User.Drawings")
		(19 "Cmts.User" user "User.Comments")
		(21 "Eco1.User" user "User.Eco1")
		(23 "Eco2.User" user "User.Eco2")
		(25 "Edge.Cuts" user "Board Geometry/Outline")
		(27 "Margin" user)
		(31 "F.CrtYd" user "Package Geometry/Place Bound Top")
		(29 "B.CrtYd" user "Package Geometry/Place Bound Bottom")
		(35 "F.Fab" user "Ref Des/Assembly Top")
		(33 "B.Fab" user "Ref Des/Assembly Bottom")
	)
	(footprint ""
		(layer "B.Cu")
		(at 74.906886 -148.476462 90)
		(property "Reference" "R293"
			(at -1.530858 1.004824 270)
			(unlocked yes)
			(layer "B.SilkS")
			(effects
				(font
					(size 0.7874 0.5842)
					(thickness 0.1524)
				)
				(justify left mirror)
			)
		)
		(property "Value" ""
			(at 0 0 90)
			(layer "B.Fab")
			(effects
				(font
					(size 1.27 1.27)
				)
				(justify mirror)
			)
		)
		(duplicate_pad_numbers_are_jumpers no)
		(fp_line
			(start 0.7874 -0.4064)
			(end -0.7874 -0.4064)
			(stroke
				(width 0.1524)
				(type default)
			)
			(layer "B.SilkS")
		)
		(fp_line
			(start -0.7874 -0.4064)
			(end -0.7874 0.4064)
			(stroke
				(width 0.1524)
				(type default)
			)
			(layer "B.SilkS")
		)
		(fp_line
			(start 0.7874 0.4064)
			(end 0.7874 -0.4064)
			(stroke
				(width 0.1524)
				(type default)
			)
			(layer "B.SilkS")
		)
		(fp_line
			(start -0.7874 0.4064)
			(end 0.7874 0.4064)
			(stroke
				(width 0.1524)
				(type default)
			)
			(layer "B.SilkS")
		)
		(fp_poly
			(pts
				(xy 0.508 0.2794) (xy 0.508 0.2286) (xy 0.635 0.2286) (xy 0.635 -0.254) (xy 0.5334 -0.254) (xy 0.5334 -0.2794)
				(xy -0.5334 -0.2794) (xy -0.5334 -0.254) (xy -0.635 -0.254) (xy -0.635 0.254) (xy -0.5334 0.254)
				(xy -0.5334 0.2794)
			)
			(stroke
				(width 0)
				(type default)
			)
			(fill no)
			(layer "B.CrtYd")
		)
		(pad "1" smd rect
			(at -0.40005 0 270)
			(size 0.4572 0.508)
			(layers "B.Cu" "B.Mask" "B.Paste")
			(net "N20822523")
		)
		(pad "2" smd rect
			(at 0.40005 0 270)
			(size 0.4572 0.508)
			(layers "B.Cu" "B.Mask" "B.Paste")
			(net "GND")
		)
	)
	(footprint ""
		(layer "B.Cu")
		(at 159.801814 -50.623978)
		(property "Reference" "C492"
			(at 1.435608 -2.73304 0)
			(unlocked yes)
			(layer "B.SilkS")
			(effects
				(font
					(size 0.7874 0.5842)
					(thickness 0.1524)
				)
				(justify left mirror)
			)
		)
		(property "Value" ""
			(at 0 0 0)
			(layer "B.Fab")
			(effects
				(font
					(size 1.27 1.27)
				)
				(justify mirror)
			)
		)
		(duplicate_pad_numbers_are_jumpers no)
		(fp_line
			(start -0.7874 -0.4064)
			(end -0.7874 0.4064)
			(stroke
				(width 0.1524)
				(type default)
			)
			(layer "B.SilkS")
		)
		(fp_line
			(start -0.7874 0.4064)
			(end 0.7874 0.4064)
			(stroke
				(width 0.1524)
				(type default)
			)
			(layer "B.SilkS")
		)
		(fp_line
			(start 0 0.381)
			(end 0 -0.381)
			(stroke
				(width 0.1524)
				(type default)
			)
			(layer "B.SilkS")
		)
		(fp_line
			(start 0.7874 -0.4064)
			(end -0.7874 -0.4064)
			(stroke
				(width 0.1524)
				(type default)
			)
			(layer "B.SilkS")
		)
		(fp_line
			(start 0.7874 0.4064)
			(end 0.7874 -0.4064)
			(stroke
				(width 0.1524)
				(type default)
			)
			(layer "B.SilkS")
		)
		(fp_poly
			(pts
				(xy 0.5334 0.254) (xy 0.635 0.254) (xy 0.635 0.2286) (xy 0.635 -0.254) (xy 0.5334 -0.254) (xy 0.5334 -0.2794)
				(xy -0.5334 -0.2794) (xy -0.5334 -0.254) (xy -0.635 -0.254) (xy -0.635 0.254) (xy -0.5334 0.254)
				(xy -0.5334 0.2794) (xy 0.508 0.2794) (xy 0.5334 0.2794)
			)
			(stroke
				(width 0)
				(type default)
			)
			(fill no)
			(layer "B.CrtYd")
		)
		(pad "1" smd rect
			(at -0.40005 0 180)
			(size 0.4572 0.508)
			(layers "B.Cu" "B.Mask" "B.Paste")
			(net "SATA_RX0_C_DP")
		)
		(pad "2" smd rect
			(at 0.40005 0 180)
			(size 0.4572 0.508)
			(layers "B.Cu" "B.Mask" "B.Paste")
			(net "SATA_A_NODE1_RX_P0")
		)
	)
	(footprint ""
		(layer "B.Cu")
		(at 58.019188 -55.092854)
		(property "Reference" "R33"
			(at 3.14579 0.043688 0)
			(unlocked yes)
			(layer "B.SilkS")
			(effects
				(font
					(size 0.7874 0.5842)
					(thickness 0.1524)
				)
				(justify left mirror)
			)
		)
		(property "Value" ""
			(at 0 0 0)
			(layer "B.Fab")
			(effects
				(font
					(size 1.27 1.27)
				)
				(justify mirror)
			)
		)
		(duplicate_pad_numbers_are_jumpers no)
		(fp_line
			(start -0.7874 -0.4064)
			(end -0.7874 0.4064)
			(stroke
				(width 0.1524)
				(type default)
			)
			(layer "B.SilkS")
		)
		(fp_line
			(start -0.7874 0.4064)
			(end 0.7874 0.4064)
			(stroke
				(width 0.1524)
				(type default)
			)
			(layer "B.SilkS")
		)
		(fp_line
			(start 0.7874 -0.4064)
			(end -0.7874 -0.4064)
			(stroke
				(width 0.1524)
				(type default)
			)
			(layer "B.SilkS")
		)
		(fp_line
			(start 0.7874 0.4064)
			(end 0.7874 -0.4064)
			(stroke
				(width 0.1524)
				(type default)
			)
			(layer "B.SilkS")
		)
		(fp_poly
			(pts
				(xy 0.508 0.2794) (xy 0.508 0.2286) (xy 0.635 0.2286) (xy 0.635 -0.254) (xy 0.5334 -0.254) (xy 0.5334 -0.2794)
				(xy -0.5334 -0.2794) (xy -0.5334 -0.254) (xy -0.635 -0.254) (xy -0.635 0.254) (xy -0.5334 0.254)
				(xy -0.5334 0.2794)
			)
			(stroke
				(width 0)
				(type default)
			)
			(fill no)
			(layer "B.CrtYd")
		)
		(pad "1" smd rect
			(at -0.40005 0 180)
			(size 0.4572 0.508)
			(layers "B.Cu" "B.Mask" "B.Paste")
			(net "M_DDR3_NODE1_MON1P")
		)
		(pad "2" smd rect
			(at 0.40005 0 180)
			(size 0.4572 0.508)
			(layers "B.Cu" "B.Mask" "B.Paste")
			(net "M_DDR3_NODE1_MON1N")
		)
	)
	(footprint ""
		(layer "B.Cu")
		(at 156.123894 -177.13833 180)
		(property "Reference" "R1306"
			(at -2.20345 2.11074 0)
			(unlocked yes)
			(layer "B.SilkS")
			(effects
				(font
					(size 0.7874 0.5842)
					(thickness 0.1524)
				)
				(justify left mirror)
			)
		)
		(property "Value" ""
			(at 0 0 0)
			(layer "B.Fab")
			(effects
				(font
					(size 1.27 1.27)
				)
				(justify mirror)
			)
		)
		(duplicate_pad_numbers_are_jumpers no)
		(fp_line
			(start 0.7874 0.4064)
			(end 0.7874 -0.4064)
			(stroke
				(width 0.1524)
				(type default)
			)
			(layer "B.SilkS")
		)
		(fp_line
			(start 0.7874 -0.4064)
			(end -0.7874 -0.4064)
			(stroke
				(width 0.1524)
				(type default)
			)
			(layer "B.SilkS")
		)
		(fp_line
			(start -0.7874 0.4064)
			(end 0.7874 0.4064)
			(stroke
				(width 0.1524)
				(type default)
			)
			(layer "B.SilkS")
		)
		(fp_line
			(start -0.7874 -0.4064)
			(end -0.7874 0.4064)
			(stroke
				(width 0.1524)
				(type default)
			)
			(layer "B.SilkS")
		)
		(fp_poly
			(pts
				(xy 0.508 0.2794) (xy 0.508 0.2286) (xy 0.635 0.2286) (xy 0.635 -0.254) (xy 0.5334 -0.254) (xy 0.5334 -0.2794)
				(xy -0.5334 -0.2794) (xy -0.5334 -0.254) (xy -0.635 -0.254) (xy -0.635 0.254) (xy -0.5334 0.254)
				(xy -0.5334 0.2794)
			)
			(stroke
				(width 0)
				(type default)
			)
			(fill no)
			(layer "B.CrtYd")
		)
		(pad "1" smd rect
			(at -0.40005 0)
			(size 0.4572 0.508)
			(layers "B.Cu" "B.Mask" "B.Paste")
			(net "GND")
		)
		(pad "2" smd rect
			(at 0.40005 0)
			(size 0.4572 0.508)
			(layers "B.Cu" "B.Mask" "B.Paste")
			(net "N54365764")
		)
	)
	(footprint ""
		(layer "B.Cu")
		(at 145.65376 -184.951624 90)
		(property "Reference" "R966"
			(at 4.357624 -2.55905 270)
			(unlocked yes)
			(layer "B.SilkS")
			(effects
				(font
					(size 0.7874 0.5842)
					(thickness 0.1524)
				)
				(justify left mirror)
			)
		)
		(property "Value" ""
			(at 0 0 90)
			(layer "B.Fab")
			(effects
				(font
					(size 1.27 1.27)
				)
				(justify mirror)
			)
		)
		(duplicate_pad_numbers_are_jumpers no)
		(fp_line
			(start 0.7874 -0.4064)
			(end -0.7874 -0.4064)
			(stroke
				(width 0.1524)
				(type default)
			)
			(layer "B.SilkS")
		)
		(fp_line
			(start -0.7874 -0.4064)
			(end -0.7874 0.4064)
			(stroke
				(width 0.1524)
				(type default)
			)
			(layer "B.SilkS")
		)
		(fp_line
			(start 0.7874 0.4064)
			(end 0.7874 -0.4064)
			(stroke
				(width 0.1524)
				(type default)
			)
			(layer "B.SilkS")
		)
		(fp_line
			(start -0.7874 0.4064)
			(end 0.7874 0.4064)
			(stroke
				(width 0.1524)
				(type default)
			)
			(layer "B.SilkS")
		)
		(fp_poly
			(pts
				(xy 0.508 0.2794) (xy 0.508 0.2286) (xy 0.635 0.2286) (xy 0.635 -0.254) (xy 0.5334 -0.254) (xy 0.5334 -0.2794)
				(xy -0.5334 -0.2794) (xy -0.5334 -0.254) (xy -0.635 -0.254) (xy -0.635 0.254) (xy -0.5334 0.254)
				(xy -0.5334 0.2794)
			)
			(stroke
				(width 0)
				(type default)
			)
			(fill no)
			(layer "B.CrtYd")
		)
		(pad "1" smd rect
			(at -0.40005 0 270)
			(size 0.4572 0.508)
			(layers "B.Cu" "B.Mask" "B.Paste")
			(net "UART_T11_NODE2_TXD")
		)
		(pad "2" smd rect
			(at 0.40005 0 270)
			(size 0.4572 0.508)
			(layers "B.Cu" "B.Mask" "B.Paste")
			(net "UART_T11_NODE2_TXD_R")
		)
	)
	(footprint ""
		(layer "B.Cu")
		(at 70.31355 -92.822268 90)
		(property "Reference" "R85"
			(at -1.309116 2.74828 270)
			(unlocked yes)
			(layer "B.SilkS")
			(effects
				(font
					(size 0.7874 0.5842)
					(thickness 0.1524)
				)
				(justify left mirror)
			)
		)
		(property "Value" ""
			(at 0 0 90)
			(layer "B.Fab")
			(effects
				(font
					(size 1.27 1.27)
				)
				(justify mirror)
			)
		)
		(duplicate_pad_numbers_are_jumpers no)
		(fp_line
			(start 0.7874 -0.4064)
			(end -0.7874 -0.4064)
			(stroke
				(width 0.1524)
				(type default)
			)
			(layer "B.SilkS")
		)
		(fp_line
			(start -0.7874 -0.4064)
			(end -0.7874 0.4064)
			(stroke
				(width 0.1524)
				(type default)
			)
			(layer "B.SilkS")
		)
		(fp_line
			(start 0.7874 0.4064)
			(end 0.7874 -0.4064)
			(stroke
				(width 0.1524)
				(type default)
			)
			(layer "B.SilkS")
		)
		(fp_line
			(start -0.7874 0.4064)
			(end 0.7874 0.4064)
			(stroke
				(width 0.1524)
				(type default)
			)
			(layer "B.SilkS")
		)
		(fp_poly
			(pts
				(xy 0.508 0.2794) (xy 0.508 0.2286) (xy 0.635 0.2286) (xy 0.635 -0.254) (xy 0.5334 -0.254) (xy 0.5334 -0.2794)
				(xy -0.5334 -0.2794) (xy -0.5334 -0.254) (xy -0.635 -0.254) (xy -0.635 0.254) (xy -0.5334 0.254)
				(xy -0.5334 0.2794)
			)
			(stroke
				(width 0)
				(type default)
			)
			(fill no)
			(layer "B.CrtYd")
		)
		(pad "1" smd rect
			(at -0.40005 0 270)
			(size 0.4572 0.508)
			(layers "B.Cu" "B.Mask" "B.Paste")
			(net "H_CPU_NODE1_ERR2")
		)
		(pad "2" smd rect
			(at 0.40005 0 270)
			(size 0.4572 0.508)
			(layers "B.Cu" "B.Mask" "B.Paste")
			(net "H_CPU_NODE1_ERR2_R")
		)
	)
	(footprint ""
		(layer "B.Cu")
		(at 63.10376 -185.205624 90)
		(property "Reference" "R868"
			(at 4.15163 0.159512 270)
			(unlocked yes)
			(layer "B.SilkS")
			(effects
				(font
					(size 0.7874 0.5842)
					(thickness 0.1524)
				)
				(justify left mirror)
			)
		)
		(property "Value" ""
			(at 0 0 90)
			(layer "B.Fab")
			(effects
				(font
					(size 1.27 1.27)
				)
				(justify mirror)
			)
		)
		(duplicate_pad_numbers_are_jumpers no)
		(fp_line
			(start 0.7874 -0.406146)
			(end -0.7874 -0.406146)
			(stroke
				(width 0.1524)
				(type default)
			)
			(layer "B.SilkS")
		)
		(fp_line
			(start -0.7874 -0.406146)
			(end -0.7874 0.406146)
			(stroke
				(width 0.1524)
				(type default)
			)
			(layer "B.SilkS")
		)
		(fp_line
			(start 0.7874 0.406146)
			(end 0.7874 -0.406146)
			(stroke
				(width 0.1524)
				(type default)
			)
			(layer "B.SilkS")
		)
		(fp_line
			(start -0.7874 0.406146)
			(end 0.7874 0.406146)
			(stroke
				(width 0.1524)
				(type default)
			)
			(layer "B.SilkS")
		)
		(fp_poly
			(pts
				(xy 0.508 0.2794) (xy 0.508 0.2286) (xy 0.635 0.2286) (xy 0.635 -0.254) (xy 0.5334 -0.254) (xy 0.5334 -0.2794)
				(xy -0.5334 -0.2794) (xy -0.5334 -0.254) (xy -0.635 -0.254) (xy -0.635 0.254) (xy -0.5334 0.254)
				(xy -0.5334 0.2794)
			)
			(stroke
				(width 0)
				(type default)
			)
			(fill no)
			(layer "B.CrtYd")
		)
		(pad "1" smd rect
			(at -0.40005 0 270)
			(size 0.4572 0.508)
			(layers "B.Cu" "B.Mask" "B.Paste")
			(net "T1_NODE4_EN")
		)
		(pad "2" smd rect
			(at 0.40005 0 270)
			(size 0.4572 0.508)
			(layers "B.Cu" "B.Mask" "B.Paste")
			(net "T1_NODE4_EN_R")
		)
	)
	(footprint ""
		(layer "B.Cu")
		(at 121.40184 -144.956276 180)
		(property "Reference" "C185"
			(at 1.136396 -0.943864 0)
			(unlocked yes)
			(layer "B.SilkS")
			(effects
				(font
					(size 0.7874 0.5842)
					(thickness 0.1524)
				)
				(justify left mirror)
			)
		)
		(property "Value" ""
			(at 0 0 0)
			(layer "B.Fab")
			(effects
				(font
					(size 1.27 1.27)
				)
				(justify mirror)
			)
		)
		(duplicate_pad_numbers_are_jumpers no)
		(fp_line
			(start 0.7874 0.406146)
			(end 0.7874 -0.406146)
			(stroke
				(width 0.1524)
				(type default)
			)
			(layer "B.SilkS")
		)
		(fp_line
			(start 0.7874 -0.406146)
			(end -0.7874 -0.406146)
			(stroke
				(width 0.1524)
				(type default)
			)
			(layer "B.SilkS")
		)
		(fp_line
			(start 0 0.381)
			(end 0 -0.381)
			(stroke
				(width 0.1524)
				(type default)
			)
			(layer "B.SilkS")
		)
		(fp_line
			(start -0.7874 0.406146)
			(end 0.7874 0.406146)
			(stroke
				(width 0.1524)
				(type default)
			)
			(layer "B.SilkS")
		)
		(fp_line
			(start -0.7874 -0.406146)
			(end -0.7874 0.406146)
			(stroke
				(width 0.1524)
				(type default)
			)
			(layer "B.SilkS")
		)
		(fp_poly
			(pts
				(xy 0.5334 0.254) (xy 0.635 0.254) (xy 0.635 0.2286) (xy 0.635 -0.254) (xy 0.5334 -0.254) (xy 0.5334 -0.2794)
				(xy -0.5334 -0.2794) (xy -0.5334 -0.254) (xy -0.635 -0.254) (xy -0.635 0.254) (xy -0.5334 0.254)
				(xy -0.5334 0.2794) (xy 0.508 0.2794) (xy 0.5334 0.2794)
			)
			(stroke
				(width 0)
				(type default)
			)
			(fill no)
			(layer "B.CrtYd")
		)
		(pad "1" smd rect
			(at -0.40005 0)
			(size 0.4572 0.508)
			(layers "B.Cu" "B.Mask" "B.Paste")
			(net "P2E_CPU_PCIE_SW_NODE1_RX_C_DP")
		)
		(pad "2" smd rect
			(at 0.40005 0)
			(size 0.4572 0.508)
			(layers "B.Cu" "B.Mask" "B.Paste")
			(net "P2E_CPU_PCIE_SW_NODE1_RX_DP")
		)
	)
	(footprint ""
		(layer "B.Cu")
		(at 90.81262 -166.910512)
		(property "Reference" "R785"
			(at 24.774144 20.136104 0)
			(unlocked yes)
			(layer "B.SilkS")
			(effects
				(font
					(size 0.7874 0.5842)
					(thickness 0.1524)
				)
				(justify left mirror)
			)
		)
		(property "Value" ""
			(at 0 0 0)
			(layer "B.Fab")
			(effects
				(font
					(size 1.27 1.27)
				)
				(justify mirror)
			)
		)
		(duplicate_pad_numbers_are_jumpers no)
		(fp_line
			(start -0.7874 -0.4064)
			(end -0.7874 0.4064)
			(stroke
				(width 0.1524)
				(type default)
			)
			(layer "B.SilkS")
		)
		(fp_line
			(start -0.7874 0.4064)
			(end 0.7874 0.4064)
			(stroke
				(width 0.1524)
				(type default)
			)
			(layer "B.SilkS")
		)
		(fp_line
			(start 0.7874 -0.4064)
			(end -0.7874 -0.4064)
			(stroke
				(width 0.1524)
				(type default)
			)
			(layer "B.SilkS")
		)
		(fp_line
			(start 0.7874 0.4064)
			(end 0.7874 -0.4064)
			(stroke
				(width 0.1524)
				(type default)
			)
			(layer "B.SilkS")
		)
		(fp_poly
			(pts
				(xy 0.508 0.2794) (xy 0.508 0.2286) (xy 0.635 0.2286) (xy 0.635 -0.254) (xy 0.5334 -0.254) (xy 0.5334 -0.2794)
				(xy -0.5334 -0.2794) (xy -0.5334 -0.254) (xy -0.635 -0.254) (xy -0.635 0.254) (xy -0.5334 0.254)
				(xy -0.5334 0.2794)
			)
			(stroke
				(width 0)
				(type default)
			)
			(fill no)
			(layer "B.CrtYd")
		)
		(pad "1" smd rect
			(at -0.40005 0 180)
			(size 0.4572 0.508)
			(layers "B.Cu" "B.Mask" "B.Paste")
			(net "UART_SW_S1_N")
		)
		(pad "2" smd rect
			(at 0.40005 0 180)
			(size 0.4572 0.508)
			(layers "B.Cu" "B.Mask" "B.Paste")
			(net "P3V3_NODE1")
		)
	)
	(footprint ""
		(layer "B.Cu")
		(at 55.552086 -125.819662 -90)
		(property "Reference" "L15"
			(at 53.329586 42.553636 270)
			(unlocked yes)
			(layer "B.SilkS")
			(effects
				(font
					(size 0.7874 0.5842)
					(thickness 0.1524)
				)
				(justify mirror)
			)
		)
		(property "Value" ""
			(at 0 0 90)
			(layer "B.Fab")
			(effects
				(font
					(size 1.27 1.27)
				)
				(justify mirror)
			)
		)
		(duplicate_pad_numbers_are_jumpers no)
		(fp_line
			(start -1.2954 0.635)
			(end 1.2954 0.635)
			(stroke
				(width 0.1524)
				(type default)
			)
			(layer "B.SilkS")
		)
		(fp_line
			(start -0.127 -0.5842)
			(end -0.127 0.5842)
			(stroke
				(width 0.1524)
				(type default)
			)
			(layer "B.SilkS")
		)
		(fp_line
			(start 0.127 -0.5842)
			(end 0.127 0.5842)
			(stroke
				(width 0.1524)
				(type default)
			)
			(layer "B.SilkS")
		)
		(fp_line
			(start -1.2954 -0.635)
			(end -1.2954 0.635)
			(stroke
				(width 0.1524)
				(type default)
			)
			(layer "B.SilkS")
		)
		(fp_line
			(start 1.2954 -0.635)
			(end 1.2954 0.635)
			(stroke
				(width 0.1524)
				(type default)
			)
			(layer "B.SilkS")
		)
		(fp_line
			(start 1.2954 -0.635)
			(end -1.2954 -0.635)
			(stroke
				(width 0.1524)
				(type default)
			)
			(layer "B.SilkS")
		)
		(fp_poly
			(pts
				(xy 0.9144 0.508) (xy 0.9144 0.3556) (xy 1.143 0.3556) (xy 1.143 -0.3556) (xy 0.9144 -0.3556) (xy 0.9144 -0.508)
				(xy -0.9144 -0.508) (xy -0.9144 -0.3556) (xy -1.143 -0.3556) (xy -1.143 0.3556) (xy -0.9144 0.3556)
				(xy -0.9144 0.508)
			)
			(stroke
				(width 0)
				(type default)
			)
			(fill no)
			(layer "B.CrtYd")
		)
		(pad "1" smd rect
			(at -0.7366 0)
			(size 0.7112 0.8128)
			(layers "B.Cu" "B.Mask" "B.Paste")
			(net "BMC_NODE1_MPLLAV33")
		)
		(pad "2" smd rect
			(at 0.7366 0)
			(size 0.7112 0.8128)
			(layers "B.Cu" "B.Mask" "B.Paste")
			(net "P3V3_NODE1")
		)
	)
)
